# BASEBOARD_FAB2 (Tioga Pass) — schematic netlist excerpt (pin names and nets, part order shuffled) for the footprints in the layout excerpt that follows; sources: Cadence DE-HDL packaged netlist, KiCad conversion of Wiwynn_Tioga_Pass_MB.brd

EU9E1  SPRINGVILLE  IC  pkg SM1  page 139
  LAN_PWR_GOOD  = PU_SPRV_LAN_PWR_GOOD
  NC_SI_CLK_IN  = CLK_50M_CKMNG_SPRVLLE
  NC_SI_CRS_DV  = RMII_BMC_PCH_SPRNGVLLE_CRSDV_R
  JTAG_TDO  = PU_JTAG_SPRV_TDO
  NC_SI_RXD1  = RMII_SPRNGVLLE_BMC_PCH_RXD1_R
  NC_SI_RXD0  = RMII_SPRNGVLLE_BMC_PCH_RXD0_R
  NC_SI_TX_EN  = RMII_BMC_PCH_SPRNGVLLE_TXEN
  NC_SI_TXD1  = RMII_BMC_PCH_SPRNGVLLE_TXD1
  NC_SI_TXD0  = RMII_BMC_PCH_SPRNGVLLE_TXD0
  VDD3P3(4)  = P3V3_STBY
  VDD0P9(2)  = P0V9_LAN
  NVM_SI  = SPI_NIC_MOSI_R
  NVM_SK  = SPI_NIC_SCLK_R
  NVM_SO  = SPI_NIC_MISO
  NVM_CS_N  = SPI_NIC_CS_R_N
  PE_WAKE_N  = FM_PE_SPRV_WAKE_N
  PE_RST_N  = RST_PLTRST_SPRV_R_N
  JTAG_TMS  = PU_JTAG_SPRV_TMS
  JTAG_CLK  = PU_JTAG_SPRV_TCK
  PE_TN  = PE_PCH_SPRV_RX_DN
  PE_TP  = PE_PCH_SPRV_RX_DP
  NC  = NC
  PE_RN  = PE_PCH_SPRV_TX_C_DN
  PE_RP  = PE_PCH_SPRV_TX_C_DP
  PECLKN  = CLK_100M_SPRV_DN
  PECLKP  = CLK_100M_SPRV_DP
  VDD3P3(3)  = P3V3_STBY
  DEV_OFF_N  = PU_DEV_OFF_N
  JTAG_TDI  = PU_JTAG_SPRV_TDI
  LED1  = LED_LAN_1_N
  LED0  = LED_LAN_0_N
  VDD0P9(1)  = P0V9_LAN
  LED2  = LED_LAN_2_N
  SMB_CLK  = SMB_SPRINGVILLE_STBY_LVC3_SCL
  SMB_ALRT_N  = IRQ_LOM_ALERT_N
  SMB_DATA  = SMB_SPRINGVILLE_STBY_LVC3_SDA
  CBOT  = A_CBOT
  VDD0P9_OUT  = P0V9_LAN_I210
  VDD1P5_OUT  = P1V5_LAN
  CTOP  = A_CTOP
  VDD3P3(2)  = P3V3_STBY
  VDD0P9(3)  = P0V9_LAN
  NC_SI_ARB_IN  = RMII_PCH_SPRNGVLLE_ARB_OUT
  NC_SI_ARB_OUT  = RMII_PCH_SPRNGVLLE_ARB_IN_R
  XTAL2  = XTAL_25MHZ_OUT
  XTAL1  = XTAL_25MHZ_IN_R
  VDD1P5(1)  = P1V5_LAN
  RSET  = PD_SPRV_RSET
  MDI_MINUS3_SERN  = NIC_SER_N_MDI_3_DN
  MDI_PLUS3_SERP  = NIC_SER_P_MDI_3_DP
  VDD3P3(1)  = P3V3_STBY_P1V5_LAN_I210
  MDI_MINUS2_SETN  = NIC_SET_N_MDI_2_DN
  MDI_PLUS2_SETP  = NIC_SET_P_MDI_2_DP
  MDI_MINUS1_SRDS_SIG_DET  = NIC_MDI_SPRV_RJ45_1_DN
  MDI_PLUS1_SFP_I2C_CLK  = NIC_MDI_SPRV_RJ45_1_DP
  VDD1P5(0)  = P1V5_LAN_I210
  MDI_MINUS0_SFP_I2C_DATA  = NIC_MDI_SPRV_RJ45_0_DN
  MDI_PLUS0_NC  = NIC_MDI_SPRV_RJ45_0_DP
  VDD0P9(0)  = P0V9_LAN
  SDP3  = TP_SPRV_SDP3
  SDP1_PCIE_DIS_SDP1  = FM_1GB_LOM_DISABLE_N
  SDP2  = TP_SPRV_SDP2
  SDP0  = TP_SPRV_SDP0
  VDD3P3(0)  = P3V3_STBY
  GND  = GND

(kicad_pcb
	(version 20260206)
	(generator "pcbnew")
	(generator_version "10.0")
	(general
		(thickness 1.6)
		(legacy_teardrops no)
	)
	(paper "A4")
	(title_block
		(title "Wiwynn_Tioga_Pass_MB.brd")
		(comment 1 "Tioga Pass / footprint 1033 of 4770 (EU9E1), pads 52-65 of 65")
	)
	(layers
		(0 "F.Cu" signal "TOP")
		(4 "In1.Cu" signal "L2GND")
		(6 "In2.Cu" signal "L3")
		(8 "In3.Cu" signal "L4GND")
		(10 "In4.Cu" signal "L5")
		(12 "In5.Cu" signal "L6GND")
		(14 "In6.Cu" signal "L7VCC")
		(16 "In7.Cu" signal "L8VCC")
		(18 "In8.Cu" signal "L9GND")
		(20 "In9.Cu" signal "L10")
		(22 "In10.Cu" signal "L11GND")
		(24 "In11.Cu" signal "L12")
		(26 "In12.Cu" signal "L13GND")
		(2 "B.Cu" signal "BOTTOM")
		(9 "F.Adhes" user "F.Adhesive")
		(11 "B.Adhes" user "B.Adhesive")
		(13 "F.Paste" user "Package Geometry/Pastemask Top")
		(15 "B.Paste" user "Package Geometry/Pastemask Bottom")
		(5 "F.SilkS" user "Ref Des/Silkscreen Top")
		(7 "B.SilkS" user "Ref Des/Silkscreen Bottom")
		(1 "F.Mask" user "Board Geometry/Soldermask Top")
		(3 "B.Mask" user "Board Geometry/Soldermask Bottom")
		(17 "Dwgs.User" user "User.Drawings")
		(19 "Cmts.User" user "User.Comments")
		(21 "Eco1.User" user "User.Eco1")
		(23 "Eco2.User" user "User.Eco2")
		(25 "Edge.Cuts" user "Board Geometry/Outline")
		(27 "Margin" user)
		(31 "F.CrtYd" user "Package Geometry/Place Bound Top")
		(29 "B.CrtYd" user "Package Geometry/Place Bound Bottom")
		(35 "F.Fab" user "Ref Des/Assembly Top")
		(33 "B.Fab" user "Ref Des/Assembly Bottom")
	)
	(footprint ""
		(layer "F.Cu")
		(at 484.251 -43.9674 180)
		(property "Reference" "EU9E1"
			(at 7.2644 -5.49529 0)
			(unlocked yes)
			(layer "F.SilkS")
			(effects
				(font
					(size 0.7874 0.5842)
					(thickness 0.1524)
				)
				(justify left)
			)
		)
		(property "Value" ""
			(at 0 0 180)
			(layer "F.Fab")
			(effects
				(font
					(size 1.27 1.27)
				)
			)
		)
		(duplicate_pad_numbers_are_jumpers no)
		(pad "52" smd custom
			(at 2.249932 -4.3688 180)
			(size 0.0762 0.0762)
			(layers "F.Cu" "F.Mask" "F.Paste")
			(net "NIC_SET_N_MDI_2_DN")
			(options
				(clearance outline)
				(anchor circle)
			)
			(primitives
				(gr_poly
					(pts
						(xy 0.1524 -0.381)
						(arc
							(start 0.1524 0.2286)
							(mid 0 0.381)
							(end -0.1524 0.2286)
						)
						(xy -0.1524 -0.381)
					)
					(width 0)
					(fill yes)
				)
			)
		)
		(pad "53" smd custom
			(at 1.75006 -4.3688 180)
			(size 0.0762 0.0762)
			(layers "F.Cu" "F.Mask" "F.Paste")
			(net "NIC_SET_P_MDI_2_DP")
			(options
				(clearance outline)
				(anchor circle)
			)
			(primitives
				(gr_poly
					(pts
						(xy 0.1524 -0.381)
						(arc
							(start 0.1524 0.2286)
							(mid 0 0.381)
							(end -0.1524 0.2286)
						)
						(xy -0.1524 -0.381)
					)
					(width 0)
					(fill yes)
				)
			)
		)
		(pad "54" smd custom
			(at 1.249934 -4.3688 180)
			(size 0.0762 0.0762)
			(layers "F.Cu" "F.Mask" "F.Paste")
			(net "NIC_MDI_SPRV_RJ45_1_DN")
			(options
				(clearance outline)
				(anchor circle)
			)
			(primitives
				(gr_poly
					(pts
						(xy 0.1524 -0.381)
						(arc
							(start 0.1524 0.2286)
							(mid 0 0.381)
							(end -0.1524 0.2286)
						)
						(xy -0.1524 -0.381)
					)
					(width 0)
					(fill yes)
				)
			)
		)
		(pad "55" smd custom
			(at 0.750062 -4.3688 180)
			(size 0.0762 0.0762)
			(layers "F.Cu" "F.Mask" "F.Paste")
			(net "NIC_MDI_SPRV_RJ45_1_DP")
			(options
				(clearance outline)
				(anchor circle)
			)
			(primitives
				(gr_poly
					(pts
						(xy 0.1524 -0.381)
						(arc
							(start 0.1524 0.2286)
							(mid 0 0.381)
							(end -0.1524 0.2286)
						)
						(xy -0.1524 -0.381)
					)
					(width 0)
					(fill yes)
				)
			)
		)
		(pad "56" smd custom
			(at 0.249936 -4.3688 180)
			(size 0.0762 0.0762)
			(layers "F.Cu" "F.Mask" "F.Paste")
			(net "P1V5_LAN_I210")
			(options
				(clearance outline)
				(anchor circle)
			)
			(primitives
				(gr_poly
					(pts
						(xy 0.1524 -0.381)
						(arc
							(start 0.1524 0.2286)
							(mid 0 0.381)
							(end -0.1524 0.2286)
						)
						(xy -0.1524 -0.381)
					)
					(width 0)
					(fill yes)
				)
			)
		)
		(pad "57" smd custom
			(at -0.249936 -4.3688 180)
			(size 0.0762 0.0762)
			(layers "F.Cu" "F.Mask" "F.Paste")
			(net "NIC_MDI_SPRV_RJ45_0_DN")
			(options
				(clearance outline)
				(anchor circle)
			)
			(primitives
				(gr_poly
					(pts
						(xy 0.1524 -0.381)
						(arc
							(start 0.1524 0.2286)
							(mid 0 0.381)
							(end -0.1524 0.2286)
						)
						(xy -0.1524 -0.381)
					)
					(width 0)
					(fill yes)
				)
			)
		)
		(pad "58" smd custom
			(at -0.750062 -4.3688 180)
			(size 0.0762 0.0762)
			(layers "F.Cu" "F.Mask" "F.Paste")
			(net "NIC_MDI_SPRV_RJ45_0_DP")
			(options
				(clearance outline)
				(anchor circle)
			)
			(primitives
				(gr_poly
					(pts
						(xy 0.1524 -0.381)
						(arc
							(start 0.1524 0.2286)
							(mid 0 0.381)
							(end -0.1524 0.2286)
						)
						(xy -0.1524 -0.381)
					)
					(width 0)
					(fill yes)
				)
			)
		)
		(pad "59" smd custom
			(at -1.249934 -4.3688 180)
			(size 0.0762 0.0762)
			(layers "F.Cu" "F.Mask" "F.Paste")
			(net "P0V9_LAN")
			(options
				(clearance outline)
				(anchor circle)
			)
			(primitives
				(gr_poly
					(pts
						(xy 0.1524 -0.381)
						(arc
							(start 0.1524 0.2286)
							(mid 0 0.381)
							(end -0.1524 0.2286)
						)
						(xy -0.1524 -0.381)
					)
					(width 0)
					(fill yes)
				)
			)
		)
		(pad "60" smd custom
			(at -1.75006 -4.3688 180)
			(size 0.0762 0.0762)
			(layers "F.Cu" "F.Mask" "F.Paste")
			(net "TP_SPRV_SDP3")
			(options
				(clearance outline)
				(anchor circle)
			)
			(primitives
				(gr_poly
					(pts
						(xy 0.1524 -0.381)
						(arc
							(start 0.1524 0.2286)
							(mid 0 0.381)
							(end -0.1524 0.2286)
						)
						(xy -0.1524 -0.381)
					)
					(width 0)
					(fill yes)
				)
			)
		)
		(pad "61" smd custom
			(at -2.249932 -4.3688 180)
			(size 0.0762 0.0762)
			(layers "F.Cu" "F.Mask" "F.Paste")
			(net "FM_1GB_LOM_DISABLE_N")
			(options
				(clearance outline)
				(anchor circle)
			)
			(primitives
				(gr_poly
					(pts
						(xy 0.1524 -0.381)
						(arc
							(start 0.1524 0.2286)
							(mid 0 0.381)
							(end -0.1524 0.2286)
						)
						(xy -0.1524 -0.381)
					)
					(width 0)
					(fill yes)
				)
			)
		)
		(pad "62" smd custom
			(at -2.750058 -4.3688 180)
			(size 0.0762 0.0762)
			(layers "F.Cu" "F.Mask" "F.Paste")
			(net "TP_SPRV_SDP2")
			(options
				(clearance outline)
				(anchor circle)
			)
			(primitives
				(gr_poly
					(pts
						(xy 0.1524 -0.381)
						(arc
							(start 0.1524 0.2286)
							(mid 0 0.381)
							(end -0.1524 0.2286)
						)
						(xy -0.1524 -0.381)
					)
					(width 0)
					(fill yes)
				)
			)
		)
		(pad "63" smd custom
			(at -3.24993 -4.3688 180)
			(size 0.0762 0.0762)
			(layers "F.Cu" "F.Mask" "F.Paste")
			(net "TP_SPRV_SDP0")
			(options
				(clearance outline)
				(anchor circle)
			)
			(primitives
				(gr_poly
					(pts
						(xy 0.1524 -0.381)
						(arc
							(start 0.1524 0.2286)
							(mid 0 0.381)
							(end -0.1524 0.2286)
						)
						(xy -0.1524 -0.381)
					)
					(width 0)
					(fill yes)
				)
			)
		)
		(pad "64" smd custom
			(at -3.750056 -4.3688 180)
			(size 0.0762 0.0762)
			(layers "F.Cu" "F.Mask" "F.Paste")
			(net "P3V3_STBY")
			(options
				(clearance outline)
				(anchor circle)
			)
			(primitives
				(gr_poly
					(pts
						(xy 0.1524 -0.381)
						(arc
							(start 0.1524 0.2286)
							(mid 0 0.381)
							(end -0.1524 0.2286)
						)
						(xy -0.1524 -0.381)
					)
					(width 0)
					(fill yes)
				)
			)
		)
		(pad "65" smd rect
			(at 0 0 180)
			(size 3.6068 3.6068)
			(layers "F.Cu" "F.Mask" "F.Paste")
			(net "GND")
		)
	)
)
